# BASEBOARD_FAB2 (Tioga Pass) — schematic netlist excerpt (pin names and nets, part order shuffled) for the footprints in the layout excerpt that follows; sources: Cadence DE-HDL packaged netlist, KiCad conversion of Wiwynn_Tioga_Pass_MB.brd

R1W20  RES  0.0 5% CHIP  pkg 0402  page 199 : A = A_HSC_TEMP ; B = TEMP_SENSOR_B
R7C23  RES  10.0K 1% CHIP  pkg 0402  page 118 : A = P3V3_STBY ; B = XDP_PCH_PWR_DEBUG_N
C8B8  CAP_A  0.1UF 16V 10% X7R  pkg 0402V  page 198 : A = P5V_STBY ; B = GND

(kicad_pcb
	(version 20260206)
	(generator "pcbnew")
	(generator_version "10.0")
	(general
		(thickness 1.6)
		(legacy_teardrops no)
	)
	(paper "A4")
	(title_block
		(title "Wiwynn_Tioga_Pass_MB.brd")
		(comment 1 "Tioga Pass / footprints 1319-1321 of 4770")
	)
	(layers
		(0 "F.Cu" signal "TOP")
		(4 "In1.Cu" signal "L2GND")
		(6 "In2.Cu" signal "L3")
		(8 "In3.Cu" signal "L4GND")
		(10 "In4.Cu" signal "L5")
		(12 "In5.Cu" signal "L6GND")
		(14 "In6.Cu" signal "L7VCC")
		(16 "In7.Cu" signal "L8VCC")
		(18 "In8.Cu" signal "L9GND")
		(20 "In9.Cu" signal "L10")
		(22 "In10.Cu" signal "L11GND")
		(24 "In11.Cu" signal "L12")
		(26 "In12.Cu" signal "L13GND")
		(2 "B.Cu" signal "BOTTOM")
		(9 "F.Adhes" user "F.Adhesive")
		(11 "B.Adhes" user "B.Adhesive")
		(13 "F.Paste" user "Package Geometry/Pastemask Top")
		(15 "B.Paste" user "Package Geometry/Pastemask Bottom")
		(5 "F.SilkS" user "Ref Des/Silkscreen Top")
		(7 "B.SilkS" user "Ref Des/Silkscreen Bottom")
		(1 "F.Mask" user "Board Geometry/Soldermask Top")
		(3 "B.Mask" user "Board Geometry/Soldermask Bottom")
		(17 "Dwgs.User" user "User.Drawings")
		(19 "Cmts.User" user "User.Comments")
		(21 "Eco1.User" user "User.Eco1")
		(23 "Eco2.User" user "User.Eco2")
		(25 "Edge.Cuts" user "Board Geometry/Outline")
		(27 "Margin" user)
		(31 "F.CrtYd" user "Package Geometry/Place Bound Top")
		(29 "B.CrtYd" user "Package Geometry/Place Bound Bottom")
		(35 "F.Fab" user "Ref Des/Assembly Top")
		(33 "B.Fab" user "Ref Des/Assembly Bottom")
	)
	(footprint ""
		(layer "F.Cu")
		(at 370.4463 -91.9353 180)
		(property "Reference" "R7C23"
			(at 0 0 180)
			(layer "F.SilkS")
			(hide yes)
			(effects
				(font
					(size 1.27 1.27)
				)
			)
		)
		(property "Value" ""
			(at 0 0 180)
			(layer "F.Fab")
			(effects
				(font
					(size 1.27 1.27)
				)
			)
		)
		(duplicate_pad_numbers_are_jumpers no)
		(fp_poly
			(pts
				(xy -0.2794 -0.1016) (xy 0.2794 -0.1016) (xy 0.2794 0.9906) (xy -0.2794 0.9906)
			)
			(stroke
				(width 0)
				(type default)
			)
			(fill no)
			(layer "F.CrtYd")
		)
		(fp_line
			(start 0.2794 0.9906)
			(end 0.2794 -0.1016)
			(stroke
				(width 0.1)
				(type default)
			)
			(layer "F.Fab")
		)
		(fp_line
			(start 0.2794 -0.1016)
			(end -0.2794 -0.1016)
			(stroke
				(width 0.1)
				(type default)
			)
			(layer "F.Fab")
		)
		(fp_line
			(start -0.2794 0.9906)
			(end 0.2794 0.9906)
			(stroke
				(width 0.1)
				(type default)
			)
			(layer "F.Fab")
		)
		(fp_line
			(start -0.2794 -0.1016)
			(end -0.2794 0.9906)
			(stroke
				(width 0.1)
				(type default)
			)
			(layer "F.Fab")
		)
		(pad "1" smd rect
			(at 0 0 180)
			(size 0.508 0.508)
			(layers "F.Cu" "F.Mask" "F.Paste")
			(net "P3V3_STBY")
		)
		(pad "2" smd rect
			(at 0 0.889 180)
			(size 0.508 0.508)
			(layers "F.Cu" "F.Mask" "F.Paste")
			(net "XDP_PCH_PWR_DEBUG_N")
		)
		(zone
			(layer "F.Cu")
			(hatch none 0.5)
			(connect_pads
				(clearance 0)
			)
			(min_thickness 0.25)
			(keepout
				(tracks not_allowed)
				(vias allowed)
				(pads allowed)
				(copperpour not_allowed)
				(footprints allowed)
			)
			(placement
				(enabled no)
				(sheetname "")
			)
			(fill
				(thermal_gap 0.5)
				(thermal_bridge_width 0.5)
				(island_removal_mode 0)
			)
			(polygon
				(pts
					(xy 370.7003 -92.5703) (xy 370.1923 -92.5703) (xy 370.1923 -92.1893) (xy 370.7003 -92.1893)
				)
			)
		)
		(zone
			(layer "F.Cu")
			(hatch none 0.5)
			(connect_pads
				(clearance 0)
			)
			(min_thickness 0.25)
			(keepout
				(tracks allowed)
				(vias not_allowed)
				(pads allowed)
				(copperpour not_allowed)
				(footprints allowed)
			)
			(placement
				(enabled no)
				(sheetname "")
			)
			(fill
				(thermal_gap 0.5)
				(thermal_bridge_width 0.5)
				(island_removal_mode 0)
			)
			(polygon
				(pts
					(xy 370.7003 -92.1893) (xy 370.1923 -92.1893) (xy 370.1923 -92.5703) (xy 370.7003 -92.5703)
				)
			)
		)
	)
	(footprint ""
		(layer "F.Cu")
		(at 431.622708 -127.587502 -90)
		(property "Reference" "C8B8"
			(at 0 0 270)
			(layer "F.SilkS")
			(hide yes)
			(effects
				(font
					(size 1.27 1.27)
				)
			)
		)
		(property "Value" ""
			(at 0 0 270)
			(layer "F.Fab")
			(effects
				(font
					(size 1.27 1.27)
				)
			)
		)
		(duplicate_pad_numbers_are_jumpers no)
		(fp_rect
			(start -0.3048 0.9906)
			(end 0.3048 -0.1016)
			(stroke
				(width 0)
				(type default)
			)
			(fill no)
			(layer "F.CrtYd")
		)
		(fp_line
			(start -0.3048 0.9906)
			(end 0.3048 0.9906)
			(stroke
				(width 0.1)
				(type default)
			)
			(layer "F.Fab")
		)
		(fp_line
			(start 0.3048 0.9906)
			(end 0.3048 -0.1016)
			(stroke
				(width 0.1)
				(type default)
			)
			(layer "F.Fab")
		)
		(fp_line
			(start -0.3048 -0.1016)
			(end -0.3048 0.9906)
			(stroke
				(width 0.1)
				(type default)
			)
			(layer "F.Fab")
		)
		(fp_line
			(start 0.3048 -0.1016)
			(end -0.3048 -0.1016)
			(stroke
				(width 0.1)
				(type default)
			)
			(layer "F.Fab")
		)
		(pad "1" smd rect
			(at 0 0 270)
			(size 0.508 0.508)
			(layers "F.Cu" "F.Mask" "F.Paste")
			(net "P5V_STBY")
		)
		(pad "2" smd rect
			(at 0 0.889 270)
			(size 0.508 0.508)
			(layers "F.Cu" "F.Mask" "F.Paste")
			(net "GND")
		)
		(zone
			(layer "F.Cu")
			(hatch none 0.5)
			(connect_pads
				(clearance 0)
			)
			(min_thickness 0.25)
			(keepout
				(tracks not_allowed)
				(vias allowed)
				(pads allowed)
				(copperpour not_allowed)
				(footprints allowed)
			)
			(placement
				(enabled no)
				(sheetname "")
			)
			(fill
				(thermal_gap 0.5)
				(thermal_bridge_width 0.5)
				(island_removal_mode 0)
			)
			(polygon
				(pts
					(xy 430.987708 -127.841502) (xy 430.987708 -127.333502) (xy 431.368708 -127.333502) (xy 431.368708 -127.841502)
				)
			)
		)
		(zone
			(layer "F.Cu")
			(hatch none 0.5)
			(connect_pads
				(clearance 0)
			)
			(min_thickness 0.25)
			(keepout
				(tracks allowed)
				(vias not_allowed)
				(pads allowed)
				(copperpour not_allowed)
				(footprints allowed)
			)
			(placement
				(enabled no)
				(sheetname "")
			)
			(fill
				(thermal_gap 0.5)
				(thermal_bridge_width 0.5)
				(island_removal_mode 0)
			)
			(polygon
				(pts
					(xy 430.987708 -127.841502) (xy 430.987708 -127.333502) (xy 431.368708 -127.333502) (xy 431.368708 -127.841502)
				)
			)
		)
	)
	(footprint ""
		(layer "F.Cu")
		(at 23.057612 -68.796408 90)
		(property "Reference" "R1W20"
			(at -0.8382 -0.67818 90)
			(unlocked yes)
			(layer "F.SilkS")
			(effects
				(font
					(size 0.4064 0.254)
					(thickness 0.1524)
				)
				(justify left)
			)
		)
		(property "Value" ""
			(at 0 0 90)
			(layer "F.Fab")
			(effects
				(font
					(size 1.27 1.27)
				)
			)
		)
		(duplicate_pad_numbers_are_jumpers no)
		(fp_poly
			(pts
				(xy -0.2794 -0.1016) (xy 0.2794 -0.1016) (xy 0.2794 0.9906) (xy -0.2794 0.9906)
			)
			(stroke
				(width 0)
				(type default)
			)
			(fill no)
			(layer "F.CrtYd")
		)
		(fp_line
			(start 0.2794 -0.1016)
			(end -0.2794 -0.1016)
			(stroke
				(width 0.1)
				(type default)
			)
			(layer "F.Fab")
		)
		(fp_line
			(start -0.2794 -0.1016)
			(end -0.2794 0.9906)
			(stroke
				(width 0.1)
				(type default)
			)
			(layer "F.Fab")
		)
		(fp_line
			(start 0.2794 0.9906)
			(end 0.2794 -0.1016)
			(stroke
				(width 0.1)
				(type default)
			)
			(layer "F.Fab")
		)
		(fp_line
			(start -0.2794 0.9906)
			(end 0.2794 0.9906)
			(stroke
				(width 0.1)
				(type default)
			)
			(layer "F.Fab")
		)
		(pad "1" smd rect
			(at 0 0 90)
			(size 0.508 0.508)
			(layers "F.Cu" "F.Mask" "F.Paste")
			(net "A_HSC_TEMP")
		)
		(pad "2" smd rect
			(at 0 0.889 90)
			(size 0.508 0.508)
			(layers "F.Cu" "F.Mask" "F.Paste")
			(net "TEMP_SENSOR_B")
		)
		(zone
			(layer "F.Cu")
			(hatch none 0.5)
			(connect_pads
				(clearance 0)
			)
			(min_thickness 0.25)
			(keepout
				(tracks allowed)
				(vias not_allowed)
				(pads allowed)
				(copperpour not_allowed)
				(footprints allowed)
			)
			(placement
				(enabled no)
				(sheetname "")
			)
			(fill
				(thermal_gap 0.5)
				(thermal_bridge_width 0.5)
				(island_removal_mode 0)
			)
			(polygon
				(pts
					(xy 23.311612 -68.542408) (xy 23.311612 -69.050408) (xy 23.692612 -69.050408) (xy 23.692612 -68.542408)
				)
			)
		)
		(zone
			(layer "F.Cu")
			(hatch none 0.5)
			(connect_pads
				(clearance 0)
			)
			(min_thickness 0.25)
			(keepout
				(tracks not_allowed)
				(vias allowed)
				(pads allowed)
				(copperpour not_allowed)
				(footprints allowed)
			)
			(placement
				(enabled no)
				(sheetname "")
			)
			(fill
				(thermal_gap 0.5)
				(thermal_bridge_width 0.5)
				(island_removal_mode 0)
			)
			(polygon
				(pts
					(xy 23.692612 -68.542408) (xy 23.692612 -69.050408) (xy 23.311612 -69.050408) (xy 23.311612 -68.542408)
				)
			)
		)
	)
)
